FILE_TYPE = MACRO_DRAWING;
SET COLOR_WIRE YELLOW;
SET COLOR_PROP ORANGE;
SET COLOR_DOT WHITE;
SET COLOR_ARC YELLOW;
SET COLOR_BODY GREEN;
SET COLOR_NOTE PURPLE;
SET PROP_DISPLAY VALUE;
SET PAGE_NUMBER P449;
FORCEADD PT5161LRS..1
(-7800 3850);
FORCEPROP 1 LAST LOCATION U6016
J 0
(-8150 5475);
DISPLAY 0.723404 (-8150 5475);
PAINT GREEN (-8150 5475);
FORCEPROP 0 LAST $SEC 1
J 0
(-8150 5625);
DISPLAY 0.680851 (-8150 5625);
PAINT MONO (-8150 5625);
DISPLAY INVISIBLE (-8150 5625);
FORCEPROP 0 LAST CDS_SEC 1
J 0
(-8150 5625);
DISPLAY 0.680851 (-8150 5625);
DISPLAY INVISIBLE (-8150 5625);
FORCEPROP 0 LASTPIN (-7350 5000) $PN N2
J 0
(-7340 5010);
DISPLAY 0.680851 (-7340 5010);
PAINT MONO (-7340 5010);
FORCEPROP 0 LASTPIN (-7350 4650) $PN Y2
J 0
(-7340 4660);
DISPLAY 0.680851 (-7340 4660);
PAINT MONO (-7340 4660);
FORCEPROP 0 LASTPIN (-7350 4300) $PN AG2
J 0
(-7340 4310);
DISPLAY 0.680851 (-7340 4310);
PAINT MONO (-7340 4310);
FORCEPROP 0 LASTPIN (-7350 3950) $PN AP2
J 0
(-7340 3960);
DISPLAY 0.680851 (-7340 3960);
PAINT MONO (-7340 3960);
FORCEPROP 0 LASTPIN (-7350 3600) $PN BA2
J 0
(-7340 3610);
DISPLAY 0.680851 (-7340 3610);
PAINT MONO (-7340 3610);
FORCEPROP 0 LASTPIN (-7350 3250) $PN BH2
J 0
(-7340 3260);
DISPLAY 0.680851 (-7340 3260);
PAINT MONO (-7340 3260);
FORCEPROP 0 LASTPIN (-7350 2900) $PN BR2
J 0
(-7340 2910);
DISPLAY 0.680851 (-7340 2910);
PAINT MONO (-7340 2910);
FORCEPROP 0 LASTPIN (-7350 2550) $PN CB2
J 0
(-7340 2560);
DISPLAY 0.680851 (-7340 2560);
PAINT MONO (-7340 2560);
FORCEPROP 0 LASTPIN (-7350 5100) $PN R1
J 0
(-7340 5110);
DISPLAY 0.680851 (-7340 5110);
PAINT MONO (-7340 5110);
FORCEPROP 0 LASTPIN (-7350 4750) $PN AB1
J 0
(-7340 4760);
DISPLAY 0.680851 (-7340 4760);
PAINT MONO (-7340 4760);
FORCEPROP 0 LASTPIN (-7350 4400) $PN AJ1
J 0
(-7340 4410);
DISPLAY 0.680851 (-7340 4410);
PAINT MONO (-7340 4410);
FORCEPROP 0 LASTPIN (-7350 4050) $PN AT1
J 0
(-7340 4060);
DISPLAY 0.680851 (-7340 4060);
PAINT MONO (-7340 4060);
FORCEPROP 0 LASTPIN (-7350 3700) $PN BC1
J 0
(-7340 3710);
DISPLAY 0.680851 (-7340 3710);
PAINT MONO (-7340 3710);
FORCEPROP 0 LASTPIN (-7350 3350) $PN BK1
J 0
(-7340 3360);
DISPLAY 0.680851 (-7340 3360);
PAINT MONO (-7340 3360);
FORCEPROP 0 LASTPIN (-7350 3000) $PN BU1
J 0
(-7340 3010);
DISPLAY 0.680851 (-7340 3010);
PAINT MONO (-7340 3010);
FORCEPROP 0 LASTPIN (-7350 2650) $PN CD1
J 0
(-7340 2660);
DISPLAY 0.680851 (-7340 2660);
PAINT MONO (-7340 2660);
FORCEPROP 2 LAST VALUE PT5161LRS
J 0
(-8150 5525);
DISPLAY 0.680851 (-8150 5525);
FORCEPROP 1 LAST MATERIAL IC
J 0
(-8150 5325);
DISPLAY 0.723404 (-8150 5325);
PAINT GREEN (-8150 5325);
FORCEPROP 2 LAST PART_TYPE SMLF
J 0
(-8150 5575);
DISPLAY 0.680851 (-8150 5575);
FORCEPROP 1 LAST NEEDS_NO_SIZE TRUE
J 0
(-7800 3850);
DISPLAY 0.723404 (-7800 3850);
PAINT GREEN (-7800 3850);
DISPLAY INVISIBLE (-7800 3850);
FORCEPROP 1 LAST CDS_LMAN_SYM_OUTLINE -350,1450,300,-1400
J 0
(-7800 3850);
DISPLAY 0.468085 (-7800 3850);
PAINT GREEN (-7800 3850);
DISPLAY INVISIBLE (-7800 3850);
FORCEPROP 2 LAST CDS_LIB pure_quanta
J 0
(-7800 3850);
DISPLAY INVISIBLE (-7800 3850);
FORCEPROP 1 LAST PATH I1
J 0
(-7800 3850);
DISPLAY 0.723404 (-7800 3850);
PAINT GREEN (-7800 3850);
DISPLAY INVISIBLE (-7800 3850);
FORCEPROP 1 LAST PART_NUMBER AJ051610U03
J 0
(-8150 5400);
DISPLAY 0.723404 (-8150 5400);
PAINT GREEN (-8150 5400);
DISPLAY INVISIBLE (-8150 5400);
FORCEADD TAP..1
(-6575 3600);
FORCEPROP 3 LASTPIN (-6625 3600) SIG_NAME P5E_CPU1_P2_RX_BUF_DN<11>
J 0
(-6615 3610);
DISPLAY 0.659574 (-6615 3610);
PAINT MONO (-6615 3610);
DISPLAY INVISIBLE (-6615 3610);
FORCEPROP 1 LASTPIN (-6625 3600) BN 11
J 0
(-6637 3608);
DISPLAY 0.680851 (-6637 3608);
PAINT GREEN (-6637 3608);
FORCEPROP 2 LAST CDS_LIB standard
J 0
(-6575 3600);
DISPLAY INVISIBLE (-6575 3600);
FORCEPROP 1 LAST BODY_TYPE PLUMBING
J 0
(-6575 3650);
DISPLAY 0.872340 (-6575 3650);
PAINT GREEN (-6575 3650);
DISPLAY INVISIBLE (-6575 3650);
FORCEPROP 1 LAST HDL_TAP TRUE
J 0
(-6250 3475);
DISPLAY 0.872340 (-6250 3475);
DISPLAY INVISIBLE (-6250 3475);
FORCEPROP 1 LAST PATH I10
J 0
(-6577 3600);
DISPLAY 0.872340 (-6577 3600);
PAINT GREEN (-6577 3600);
DISPLAY INVISIBLE (-6577 3600);
FORCEADD TAP..1
(-6575 3950);
FORCEPROP 3 LASTPIN (-6625 3950) SIG_NAME P5E_CPU1_P2_RX_BUF_DN<12>
J 0
(-6615 3960);
DISPLAY 0.659574 (-6615 3960);
PAINT MONO (-6615 3960);
DISPLAY INVISIBLE (-6615 3960);
FORCEPROP 1 LASTPIN (-6625 3950) BN 12
J 0
(-6637 3958);
DISPLAY 0.680851 (-6637 3958);
PAINT GREEN (-6637 3958);
FORCEPROP 2 LAST CDS_LIB standard
J 0
(-6575 3950);
DISPLAY INVISIBLE (-6575 3950);
FORCEPROP 1 LAST BODY_TYPE PLUMBING
J 0
(-6575 4000);
DISPLAY 0.872340 (-6575 4000);
PAINT GREEN (-6575 4000);
DISPLAY INVISIBLE (-6575 4000);
FORCEPROP 1 LAST HDL_TAP TRUE
J 0
(-6250 3825);
DISPLAY 0.872340 (-6250 3825);
DISPLAY INVISIBLE (-6250 3825);
FORCEPROP 1 LAST PATH I11
J 0
(-6577 3950);
DISPLAY 0.872340 (-6577 3950);
PAINT GREEN (-6577 3950);
DISPLAY INVISIBLE (-6577 3950);
FORCEADD TAP..1
(-6775 4400);
FORCEPROP 3 LASTPIN (-6825 4400) SIG_NAME P5E_CPU1_P2_RX_BUF_DP<13>
J 0
(-6815 4410);
DISPLAY 0.659574 (-6815 4410);
PAINT MONO (-6815 4410);
DISPLAY INVISIBLE (-6815 4410);
FORCEPROP 1 LASTPIN (-6825 4400) BN 13
J 0
(-6837 4408);
DISPLAY 0.680851 (-6837 4408);
PAINT GREEN (-6837 4408);
FORCEPROP 2 LAST CDS_LIB standard
J 0
(-6775 4400);
DISPLAY INVISIBLE (-6775 4400);
FORCEPROP 1 LAST BODY_TYPE PLUMBING
J 0
(-6775 4450);
DISPLAY 0.872340 (-6775 4450);
PAINT GREEN (-6775 4450);
DISPLAY INVISIBLE (-6775 4450);
FORCEPROP 1 LAST HDL_TAP TRUE
J 0
(-6450 4275);
DISPLAY 0.872340 (-6450 4275);
DISPLAY INVISIBLE (-6450 4275);
FORCEPROP 1 LAST PATH I12
J 0
(-6777 4400);
DISPLAY 0.872340 (-6777 4400);
PAINT GREEN (-6777 4400);
DISPLAY INVISIBLE (-6777 4400);
FORCEADD TAP..1
(-6575 4300);
FORCEPROP 3 LASTPIN (-6625 4300) SIG_NAME P5E_CPU1_P2_RX_BUF_DN<13>
J 0
(-6615 4310);
DISPLAY 0.659574 (-6615 4310);
PAINT MONO (-6615 4310);
DISPLAY INVISIBLE (-6615 4310);
FORCEPROP 1 LASTPIN (-6625 4300) BN 13
J 0
(-6637 4308);
DISPLAY 0.680851 (-6637 4308);
PAINT GREEN (-6637 4308);
FORCEPROP 2 LAST CDS_LIB standard
J 0
(-6575 4300);
DISPLAY INVISIBLE (-6575 4300);
FORCEPROP 1 LAST BODY_TYPE PLUMBING
J 0
(-6575 4350);
DISPLAY 0.872340 (-6575 4350);
PAINT GREEN (-6575 4350);
DISPLAY INVISIBLE (-6575 4350);
FORCEPROP 1 LAST HDL_TAP TRUE
J 0
(-6250 4175);
DISPLAY 0.872340 (-6250 4175);
DISPLAY INVISIBLE (-6250 4175);
FORCEPROP 1 LAST PATH I13
J 0
(-6577 4300);
DISPLAY 0.872340 (-6577 4300);
PAINT GREEN (-6577 4300);
DISPLAY INVISIBLE (-6577 4300);
FORCEADD TAP..1
(-6775 4750);
FORCEPROP 3 LASTPIN (-6825 4750) SIG_NAME P5E_CPU1_P2_RX_BUF_DP<14>
J 0
(-6815 4760);
DISPLAY 0.659574 (-6815 4760);
PAINT MONO (-6815 4760);
DISPLAY INVISIBLE (-6815 4760);
FORCEPROP 1 LASTPIN (-6825 4750) BN 14
J 0
(-6837 4758);
DISPLAY 0.680851 (-6837 4758);
PAINT GREEN (-6837 4758);
FORCEPROP 2 LAST CDS_LIB standard
J 0
(-6775 4750);
DISPLAY INVISIBLE (-6775 4750);
FORCEPROP 1 LAST BODY_TYPE PLUMBING
J 0
(-6775 4800);
DISPLAY 0.872340 (-6775 4800);
PAINT GREEN (-6775 4800);
DISPLAY INVISIBLE (-6775 4800);
FORCEPROP 1 LAST HDL_TAP TRUE
J 0
(-6450 4625);
DISPLAY 0.872340 (-6450 4625);
DISPLAY INVISIBLE (-6450 4625);
FORCEPROP 1 LAST PATH I14
J 0
(-6777 4750);
DISPLAY 0.872340 (-6777 4750);
PAINT GREEN (-6777 4750);
DISPLAY INVISIBLE (-6777 4750);
FORCEADD TAP..1
(-6575 4650);
FORCEPROP 3 LASTPIN (-6625 4650) SIG_NAME P5E_CPU1_P2_RX_BUF_DN<14>
J 0
(-6615 4660);
DISPLAY 0.659574 (-6615 4660);
PAINT MONO (-6615 4660);
DISPLAY INVISIBLE (-6615 4660);
FORCEPROP 1 LASTPIN (-6625 4650) BN 14
J 0
(-6637 4658);
DISPLAY 0.680851 (-6637 4658);
PAINT GREEN (-6637 4658);
FORCEPROP 2 LAST CDS_LIB standard
J 0
(-6575 4650);
DISPLAY INVISIBLE (-6575 4650);
FORCEPROP 1 LAST BODY_TYPE PLUMBING
J 0
(-6575 4700);
DISPLAY 0.872340 (-6575 4700);
PAINT GREEN (-6575 4700);
DISPLAY INVISIBLE (-6575 4700);
FORCEPROP 1 LAST HDL_TAP TRUE
J 0
(-6250 4525);
DISPLAY 0.872340 (-6250 4525);
DISPLAY INVISIBLE (-6250 4525);
FORCEPROP 1 LAST PATH I15
J 0
(-6577 4650);
DISPLAY 0.872340 (-6577 4650);
PAINT GREEN (-6577 4650);
DISPLAY INVISIBLE (-6577 4650);
FORCEADD TAP..1
(-6575 5000);
FORCEPROP 3 LASTPIN (-6625 5000) SIG_NAME P5E_CPU1_P2_RX_BUF_DN<15>
J 0
(-6615 5010);
DISPLAY 0.659574 (-6615 5010);
PAINT MONO (-6615 5010);
DISPLAY INVISIBLE (-6615 5010);
FORCEPROP 1 LASTPIN (-6625 5000) BN 15
J 0
(-6637 5008);
DISPLAY 0.680851 (-6637 5008);
PAINT GREEN (-6637 5008);
FORCEPROP 2 LAST CDS_LIB standard
J 0
(-6575 5000);
DISPLAY INVISIBLE (-6575 5000);
FORCEPROP 1 LAST BODY_TYPE PLUMBING
J 0
(-6575 5050);
DISPLAY 0.872340 (-6575 5050);
PAINT GREEN (-6575 5050);
DISPLAY INVISIBLE (-6575 5050);
FORCEPROP 1 LAST HDL_TAP TRUE
J 0
(-6250 4875);
DISPLAY 0.872340 (-6250 4875);
DISPLAY INVISIBLE (-6250 4875);
FORCEPROP 1 LAST PATH I16
J 0
(-6577 5000);
DISPLAY 0.872340 (-6577 5000);
PAINT GREEN (-6577 5000);
DISPLAY INVISIBLE (-6577 5000);
FORCEADD TAP..1
(-6775 5100);
FORCEPROP 3 LASTPIN (-6825 5100) SIG_NAME P5E_CPU1_P2_RX_BUF_DP<15>
J 0
(-6815 5110);
DISPLAY 0.659574 (-6815 5110);
PAINT MONO (-6815 5110);
DISPLAY INVISIBLE (-6815 5110);
FORCEPROP 1 LASTPIN (-6825 5100) BN 15
J 0
(-6837 5108);
DISPLAY 0.680851 (-6837 5108);
PAINT GREEN (-6837 5108);
FORCEPROP 2 LAST CDS_LIB standard
J 0
(-6775 5100);
DISPLAY INVISIBLE (-6775 5100);
FORCEPROP 1 LAST BODY_TYPE PLUMBING
J 0
(-6775 5150);
DISPLAY 0.872340 (-6775 5150);
PAINT GREEN (-6775 5150);
DISPLAY INVISIBLE (-6775 5150);
FORCEPROP 1 LAST HDL_TAP TRUE
J 0
(-6450 4975);
DISPLAY 0.872340 (-6450 4975);
DISPLAY INVISIBLE (-6450 4975);
FORCEPROP 1 LAST PATH I17
J 0
(-6777 5100);
DISPLAY 0.872340 (-6777 5100);
PAINT GREEN (-6777 5100);
DISPLAY INVISIBLE (-6777 5100);
FORCEADD OFFPAGE..1
R 2
(-5550 5125);
FORCEPROP 2 LAST $XR0 119 
J 0
(-5364 5125);
DISPLAY 0.638298 (-5364 5125);
PAINT MONO (-5364 5125);
FORCEPROP 2 LAST CDS_LIB standard
J 0
(-5550 5125);
DISPLAY INVISIBLE (-5550 5125);
FORCEPROP 1 LAST OFFPAGE TRUE
J 2
(-5875 5000);
DISPLAY 0.872340 (-5875 5000);
DISPLAY INVISIBLE (-5875 5000);
FORCEPROP 1 LAST COMMENT_BODY TRUE
J 2
(-5675 5025);
DISPLAY 0.872340 (-5675 5025);
PAINT GREEN (-5675 5025);
DISPLAY INVISIBLE (-5675 5025);
FORCEPROP 2 LAST PATH I18
J 0
(-5375 5200);
DISPLAY 0.680851 (-5375 5200);
DISPLAY INVISIBLE (-5375 5200);
FORCEADD OFFPAGE..1
R 2
(-5550 5200);
FORCEPROP 2 LAST $XR0 119 
J 0
(-5364 5200);
DISPLAY 0.638298 (-5364 5200);
PAINT MONO (-5364 5200);
FORCEPROP 2 LAST CDS_LIB standard
J 0
(-5550 5200);
DISPLAY INVISIBLE (-5550 5200);
FORCEPROP 1 LAST OFFPAGE TRUE
J 2
(-5875 5075);
DISPLAY 0.872340 (-5875 5075);
DISPLAY INVISIBLE (-5875 5075);
FORCEPROP 1 LAST COMMENT_BODY TRUE
J 2
(-5675 5100);
DISPLAY 0.872340 (-5675 5100);
PAINT GREEN (-5675 5100);
DISPLAY INVISIBLE (-5675 5100);
FORCEPROP 2 LAST PATH I19
J 0
(-5375 5275);
DISPLAY 0.680851 (-5375 5275);
DISPLAY INVISIBLE (-5375 5275);
FORCEADD TAP..1
(-6775 2650);
FORCEPROP 3 LASTPIN (-6825 2650) SIG_NAME P5E_CPU1_P2_RX_BUF_DP<8>
J 0
(-6815 2660);
DISPLAY 0.659574 (-6815 2660);
PAINT MONO (-6815 2660);
DISPLAY INVISIBLE (-6815 2660);
FORCEPROP 1 LASTPIN (-6825 2650) BN 8
J 0
(-6837 2658);
DISPLAY 0.680851 (-6837 2658);
PAINT GREEN (-6837 2658);
FORCEPROP 2 LAST CDS_LIB standard
J 0
(-6775 2650);
DISPLAY INVISIBLE (-6775 2650);
FORCEPROP 1 LAST BODY_TYPE PLUMBING
J 0
(-6775 2700);
DISPLAY 0.872340 (-6775 2700);
PAINT GREEN (-6775 2700);
DISPLAY INVISIBLE (-6775 2700);
FORCEPROP 1 LAST HDL_TAP TRUE
J 0
(-6450 2525);
DISPLAY 0.872340 (-6450 2525);
DISPLAY INVISIBLE (-6450 2525);
FORCEPROP 1 LAST PATH I2
J 0
(-6777 2650);
DISPLAY 0.872340 (-6777 2650);
PAINT GREEN (-6777 2650);
DISPLAY INVISIBLE (-6777 2650);
FORCEADD TAP..1
(-2325 2675);
FORCEPROP 3 LASTPIN (-2375 2675) SIG_NAME P5E_CPU1_P2_RX_BUF_DP<0>
J 0
(-2365 2685);
DISPLAY 0.659574 (-2365 2685);
PAINT MONO (-2365 2685);
DISPLAY INVISIBLE (-2365 2685);
FORCEPROP 1 LASTPIN (-2375 2675) BN 0
J 0
(-2387 2683);
DISPLAY 0.680851 (-2387 2683);
PAINT GREEN (-2387 2683);
FORCEPROP 2 LAST CDS_LIB standard
J 0
(-2325 2675);
DISPLAY INVISIBLE (-2325 2675);
FORCEPROP 1 LAST BODY_TYPE PLUMBING
J 0
(-2325 2725);
DISPLAY 0.872340 (-2325 2725);
PAINT GREEN (-2325 2725);
DISPLAY INVISIBLE (-2325 2725);
FORCEPROP 1 LAST HDL_TAP TRUE
J 0
(-2000 2550);
DISPLAY 0.872340 (-2000 2550);
DISPLAY INVISIBLE (-2000 2550);
FORCEPROP 1 LAST PATH I20
J 0
(-2327 2675);
DISPLAY 0.872340 (-2327 2675);
PAINT GREEN (-2327 2675);
DISPLAY INVISIBLE (-2327 2675);
FORCEADD TAP..1
(-2325 3025);
FORCEPROP 3 LASTPIN (-2375 3025) SIG_NAME P5E_CPU1_P2_RX_BUF_DP<1>
J 0
(-2365 3035);
DISPLAY 0.659574 (-2365 3035);
PAINT MONO (-2365 3035);
DISPLAY INVISIBLE (-2365 3035);
FORCEPROP 1 LASTPIN (-2375 3025) BN 1
J 0
(-2387 3033);
DISPLAY 0.680851 (-2387 3033);
PAINT GREEN (-2387 3033);
FORCEPROP 2 LAST CDS_LIB standard
J 0
(-2325 3025);
DISPLAY INVISIBLE (-2325 3025);
FORCEPROP 1 LAST BODY_TYPE PLUMBING
J 0
(-2325 3075);
DISPLAY 0.872340 (-2325 3075);
PAINT GREEN (-2325 3075);
DISPLAY INVISIBLE (-2325 3075);
FORCEPROP 1 LAST HDL_TAP TRUE
J 0
(-2000 2900);
DISPLAY 0.872340 (-2000 2900);
DISPLAY INVISIBLE (-2000 2900);
FORCEPROP 1 LAST PATH I21
J 0
(-2327 3025);
DISPLAY 0.872340 (-2327 3025);
PAINT GREEN (-2327 3025);
DISPLAY INVISIBLE (-2327 3025);
FORCEADD TAP..1
(-2325 3375);
FORCEPROP 3 LASTPIN (-2375 3375) SIG_NAME P5E_CPU1_P2_RX_BUF_DP<2>
J 0
(-2365 3385);
DISPLAY 0.659574 (-2365 3385);
PAINT MONO (-2365 3385);
DISPLAY INVISIBLE (-2365 3385);
FORCEPROP 1 LASTPIN (-2375 3375) BN 2
J 0
(-2387 3383);
DISPLAY 0.680851 (-2387 3383);
PAINT GREEN (-2387 3383);
FORCEPROP 2 LAST CDS_LIB standard
J 0
(-2325 3375);
DISPLAY INVISIBLE (-2325 3375);
FORCEPROP 1 LAST BODY_TYPE PLUMBING
J 0
(-2325 3425);
DISPLAY 0.872340 (-2325 3425);
PAINT GREEN (-2325 3425);
DISPLAY INVISIBLE (-2325 3425);
FORCEPROP 1 LAST HDL_TAP TRUE
J 0
(-2000 3250);
DISPLAY 0.872340 (-2000 3250);
DISPLAY INVISIBLE (-2000 3250);
FORCEPROP 1 LAST PATH I22
J 0
(-2327 3375);
DISPLAY 0.872340 (-2327 3375);
PAINT GREEN (-2327 3375);
DISPLAY INVISIBLE (-2327 3375);
FORCEADD TAP..1
(-2325 3725);
FORCEPROP 3 LASTPIN (-2375 3725) SIG_NAME P5E_CPU1_P2_RX_BUF_DP<3>
J 0
(-2365 3735);
DISPLAY 0.659574 (-2365 3735);
PAINT MONO (-2365 3735);
DISPLAY INVISIBLE (-2365 3735);
FORCEPROP 1 LASTPIN (-2375 3725) BN 3
J 0
(-2387 3733);
DISPLAY 0.680851 (-2387 3733);
PAINT GREEN (-2387 3733);
FORCEPROP 2 LAST CDS_LIB standard
J 0
(-2325 3725);
DISPLAY INVISIBLE (-2325 3725);
FORCEPROP 1 LAST BODY_TYPE PLUMBING
J 0
(-2325 3775);
DISPLAY 0.872340 (-2325 3775);
PAINT GREEN (-2325 3775);
DISPLAY INVISIBLE (-2325 3775);
FORCEPROP 1 LAST HDL_TAP TRUE
J 0
(-2000 3600);
DISPLAY 0.872340 (-2000 3600);
DISPLAY INVISIBLE (-2000 3600);
FORCEPROP 1 LAST PATH I23
J 0
(-2327 3725);
DISPLAY 0.872340 (-2327 3725);
PAINT GREEN (-2327 3725);
DISPLAY INVISIBLE (-2327 3725);
FORCEADD TAP..1
(-2125 2575);
FORCEPROP 3 LASTPIN (-2175 2575) SIG_NAME P5E_CPU1_P2_RX_BUF_DN<0>
J 0
(-2165 2585);
DISPLAY 0.659574 (-2165 2585);
PAINT MONO (-2165 2585);
DISPLAY INVISIBLE (-2165 2585);
FORCEPROP 1 LASTPIN (-2175 2575) BN 0
J 0
(-2187 2583);
DISPLAY 0.680851 (-2187 2583);
PAINT GREEN (-2187 2583);
FORCEPROP 2 LAST CDS_LIB standard
J 0
(-2125 2575);
DISPLAY INVISIBLE (-2125 2575);
FORCEPROP 1 LAST BODY_TYPE PLUMBING
J 0
(-2125 2625);
DISPLAY 0.872340 (-2125 2625);
PAINT GREEN (-2125 2625);
DISPLAY INVISIBLE (-2125 2625);
FORCEPROP 1 LAST HDL_TAP TRUE
J 0
(-1800 2450);
DISPLAY 0.872340 (-1800 2450);
DISPLAY INVISIBLE (-1800 2450);
FORCEPROP 1 LAST PATH I24
J 0
(-2127 2575);
DISPLAY 0.872340 (-2127 2575);
PAINT GREEN (-2127 2575);
DISPLAY INVISIBLE (-2127 2575);
FORCEADD TAP..1
(-2125 2925);
FORCEPROP 3 LASTPIN (-2175 2925) SIG_NAME P5E_CPU1_P2_RX_BUF_DN<1>
J 0
(-2165 2935);
DISPLAY 0.659574 (-2165 2935);
PAINT MONO (-2165 2935);
DISPLAY INVISIBLE (-2165 2935);
FORCEPROP 1 LASTPIN (-2175 2925) BN 1
J 0
(-2187 2933);
DISPLAY 0.680851 (-2187 2933);
PAINT GREEN (-2187 2933);
FORCEPROP 2 LAST CDS_LIB standard
J 0
(-2125 2925);
DISPLAY INVISIBLE (-2125 2925);
FORCEPROP 1 LAST BODY_TYPE PLUMBING
J 0
(-2125 2975);
DISPLAY 0.872340 (-2125 2975);
PAINT GREEN (-2125 2975);
DISPLAY INVISIBLE (-2125 2975);
FORCEPROP 1 LAST HDL_TAP TRUE
J 0
(-1800 2800);
DISPLAY 0.872340 (-1800 2800);
DISPLAY INVISIBLE (-1800 2800);
FORCEPROP 1 LAST PATH I25
J 0
(-2127 2925);
DISPLAY 0.872340 (-2127 2925);
PAINT GREEN (-2127 2925);
DISPLAY INVISIBLE (-2127 2925);
FORCEADD TAP..1
(-2125 3275);
FORCEPROP 3 LASTPIN (-2175 3275) SIG_NAME P5E_CPU1_P2_RX_BUF_DN<2>
J 0
(-2165 3285);
DISPLAY 0.659574 (-2165 3285);
PAINT MONO (-2165 3285);
DISPLAY INVISIBLE (-2165 3285);
FORCEPROP 1 LASTPIN (-2175 3275) BN 2
J 0
(-2187 3283);
DISPLAY 0.680851 (-2187 3283);
PAINT GREEN (-2187 3283);
FORCEPROP 2 LAST CDS_LIB standard
J 0
(-2125 3275);
DISPLAY INVISIBLE (-2125 3275);
FORCEPROP 1 LAST BODY_TYPE PLUMBING
J 0
(-2125 3325);
DISPLAY 0.872340 (-2125 3325);
PAINT GREEN (-2125 3325);
DISPLAY INVISIBLE (-2125 3325);
FORCEPROP 1 LAST HDL_TAP TRUE
J 0
(-1800 3150);
DISPLAY 0.872340 (-1800 3150);
DISPLAY INVISIBLE (-1800 3150);
FORCEPROP 1 LAST PATH I26
J 0
(-2127 3275);
DISPLAY 0.872340 (-2127 3275);
PAINT GREEN (-2127 3275);
DISPLAY INVISIBLE (-2127 3275);
FORCEADD TAP..1
(-2125 3625);
FORCEPROP 3 LASTPIN (-2175 3625) SIG_NAME P5E_CPU1_P2_RX_BUF_DN<3>
J 0
(-2165 3635);
DISPLAY 0.659574 (-2165 3635);
PAINT MONO (-2165 3635);
DISPLAY INVISIBLE (-2165 3635);
FORCEPROP 1 LASTPIN (-2175 3625) BN 3
J 0
(-2187 3633);
DISPLAY 0.680851 (-2187 3633);
PAINT GREEN (-2187 3633);
FORCEPROP 2 LAST CDS_LIB standard
J 0
(-2125 3625);
DISPLAY INVISIBLE (-2125 3625);
FORCEPROP 1 LAST BODY_TYPE PLUMBING
J 0
(-2125 3675);
DISPLAY 0.872340 (-2125 3675);
PAINT GREEN (-2125 3675);
DISPLAY INVISIBLE (-2125 3675);
FORCEPROP 1 LAST HDL_TAP TRUE
J 0
(-1800 3500);
DISPLAY 0.872340 (-1800 3500);
DISPLAY INVISIBLE (-1800 3500);
FORCEPROP 1 LAST PATH I27
J 0
(-2127 3625);
DISPLAY 0.872340 (-2127 3625);
PAINT GREEN (-2127 3625);
DISPLAY INVISIBLE (-2127 3625);
FORCEADD TAP..1
(-2125 3975);
FORCEPROP 3 LASTPIN (-2175 3975) SIG_NAME P5E_CPU1_P2_RX_BUF_DN<4>
J 0
(-2165 3985);
DISPLAY 0.659574 (-2165 3985);
PAINT MONO (-2165 3985);
DISPLAY INVISIBLE (-2165 3985);
FORCEPROP 1 LASTPIN (-2175 3975) BN 4
J 0
(-2187 3983);
DISPLAY 0.680851 (-2187 3983);
PAINT GREEN (-2187 3983);
FORCEPROP 2 LAST CDS_LIB standard
J 0
(-2125 3975);
DISPLAY INVISIBLE (-2125 3975);
FORCEPROP 1 LAST BODY_TYPE PLUMBING
J 0
(-2125 4025);
DISPLAY 0.872340 (-2125 4025);
PAINT GREEN (-2125 4025);
DISPLAY INVISIBLE (-2125 4025);
FORCEPROP 1 LAST HDL_TAP TRUE
J 0
(-1800 3850);
DISPLAY 0.872340 (-1800 3850);
DISPLAY INVISIBLE (-1800 3850);
FORCEPROP 1 LAST PATH I28
J 0
(-2127 3975);
DISPLAY 0.872340 (-2127 3975);
PAINT GREEN (-2127 3975);
DISPLAY INVISIBLE (-2127 3975);
FORCEADD TAP..1
(-2325 4075);
FORCEPROP 3 LASTPIN (-2375 4075) SIG_NAME P5E_CPU1_P2_RX_BUF_DP<4>
J 0
(-2365 4085);
DISPLAY 0.659574 (-2365 4085);
PAINT MONO (-2365 4085);
DISPLAY INVISIBLE (-2365 4085);
FORCEPROP 1 LASTPIN (-2375 4075) BN 4
J 0
(-2387 4083);
DISPLAY 0.680851 (-2387 4083);
PAINT GREEN (-2387 4083);
FORCEPROP 2 LAST CDS_LIB standard
J 0
(-2325 4075);
DISPLAY INVISIBLE (-2325 4075);
FORCEPROP 1 LAST BODY_TYPE PLUMBING
J 0
(-2325 4125);
DISPLAY 0.872340 (-2325 4125);
PAINT GREEN (-2325 4125);
DISPLAY INVISIBLE (-2325 4125);
FORCEPROP 1 LAST HDL_TAP TRUE
J 0
(-2000 3950);
DISPLAY 0.872340 (-2000 3950);
DISPLAY INVISIBLE (-2000 3950);
FORCEPROP 1 LAST PATH I29
J 0
(-2327 4075);
DISPLAY 0.872340 (-2327 4075);
PAINT GREEN (-2327 4075);
DISPLAY INVISIBLE (-2327 4075);
FORCEADD TAP..1
(-6775 3000);
FORCEPROP 3 LASTPIN (-6825 3000) SIG_NAME P5E_CPU1_P2_RX_BUF_DP<9>
J 0
(-6815 3010);
DISPLAY 0.659574 (-6815 3010);
PAINT MONO (-6815 3010);
DISPLAY INVISIBLE (-6815 3010);
FORCEPROP 1 LASTPIN (-6825 3000) BN 9
J 0
(-6837 3008);
DISPLAY 0.680851 (-6837 3008);
PAINT GREEN (-6837 3008);
FORCEPROP 2 LAST CDS_LIB standard
J 0
(-6775 3000);
DISPLAY INVISIBLE (-6775 3000);
FORCEPROP 1 LAST BODY_TYPE PLUMBING
J 0
(-6775 3050);
DISPLAY 0.872340 (-6775 3050);
PAINT GREEN (-6775 3050);
DISPLAY INVISIBLE (-6775 3050);
FORCEPROP 1 LAST HDL_TAP TRUE
J 0
(-6450 2875);
DISPLAY 0.872340 (-6450 2875);
DISPLAY INVISIBLE (-6450 2875);
FORCEPROP 1 LAST PATH I3
J 0
(-6777 3000);
DISPLAY 0.872340 (-6777 3000);
PAINT GREEN (-6777 3000);
DISPLAY INVISIBLE (-6777 3000);
FORCEADD TAP..1
(-2325 4425);
FORCEPROP 3 LASTPIN (-2375 4425) SIG_NAME P5E_CPU1_P2_RX_BUF_DP<5>
J 0
(-2365 4435);
DISPLAY 0.659574 (-2365 4435);
PAINT MONO (-2365 4435);
DISPLAY INVISIBLE (-2365 4435);
FORCEPROP 1 LASTPIN (-2375 4425) BN 5
J 0
(-2387 4433);
DISPLAY 0.680851 (-2387 4433);
PAINT GREEN (-2387 4433);
FORCEPROP 2 LAST CDS_LIB standard
J 0
(-2325 4425);
DISPLAY INVISIBLE (-2325 4425);
FORCEPROP 1 LAST BODY_TYPE PLUMBING
J 0
(-2325 4475);
DISPLAY 0.872340 (-2325 4475);
PAINT GREEN (-2325 4475);
DISPLAY INVISIBLE (-2325 4475);
FORCEPROP 1 LAST HDL_TAP TRUE
J 0
(-2000 4300);
DISPLAY 0.872340 (-2000 4300);
DISPLAY INVISIBLE (-2000 4300);
FORCEPROP 1 LAST PATH I30
J 0
(-2327 4425);
DISPLAY 0.872340 (-2327 4425);
PAINT GREEN (-2327 4425);
DISPLAY INVISIBLE (-2327 4425);
FORCEADD TAP..1
(-2325 4775);
FORCEPROP 3 LASTPIN (-2375 4775) SIG_NAME P5E_CPU1_P2_RX_BUF_DP<6>
J 0
(-2365 4785);
DISPLAY 0.659574 (-2365 4785);
PAINT MONO (-2365 4785);
DISPLAY INVISIBLE (-2365 4785);
FORCEPROP 1 LASTPIN (-2375 4775) BN 6
J 0
(-2387 4783);
DISPLAY 0.680851 (-2387 4783);
PAINT GREEN (-2387 4783);
FORCEPROP 2 LAST CDS_LIB standard
J 0
(-2325 4775);
DISPLAY INVISIBLE (-2325 4775);
FORCEPROP 1 LAST BODY_TYPE PLUMBING
J 0
(-2325 4825);
DISPLAY 0.872340 (-2325 4825);
PAINT GREEN (-2325 4825);
DISPLAY INVISIBLE (-2325 4825);
FORCEPROP 1 LAST HDL_TAP TRUE
J 0
(-2000 4650);
DISPLAY 0.872340 (-2000 4650);
DISPLAY INVISIBLE (-2000 4650);
FORCEPROP 1 LAST PATH I31
J 0
(-2327 4775);
DISPLAY 0.872340 (-2327 4775);
PAINT GREEN (-2327 4775);
DISPLAY INVISIBLE (-2327 4775);
FORCEADD TAP..1
(-2325 5125);
FORCEPROP 3 LASTPIN (-2375 5125) SIG_NAME P5E_CPU1_P2_RX_BUF_DP<7>
J 0
(-2365 5135);
DISPLAY 0.659574 (-2365 5135);
PAINT MONO (-2365 5135);
DISPLAY INVISIBLE (-2365 5135);
FORCEPROP 1 LASTPIN (-2375 5125) BN 7
J 0
(-2387 5133);
DISPLAY 0.680851 (-2387 5133);
PAINT GREEN (-2387 5133);
FORCEPROP 2 LAST CDS_LIB standard
J 0
(-2325 5125);
DISPLAY INVISIBLE (-2325 5125);
FORCEPROP 1 LAST BODY_TYPE PLUMBING
J 0
(-2325 5175);
DISPLAY 0.872340 (-2325 5175);
PAINT GREEN (-2325 5175);
DISPLAY INVISIBLE (-2325 5175);
FORCEPROP 1 LAST HDL_TAP TRUE
J 0
(-2000 5000);
DISPLAY 0.872340 (-2000 5000);
DISPLAY INVISIBLE (-2000 5000);
FORCEPROP 1 LAST PATH I32
J 0
(-2327 5125);
DISPLAY 0.872340 (-2327 5125);
PAINT GREEN (-2327 5125);
DISPLAY INVISIBLE (-2327 5125);
FORCEADD TAP..1
(-2125 4325);
FORCEPROP 3 LASTPIN (-2175 4325) SIG_NAME P5E_CPU1_P2_RX_BUF_DN<5>
J 0
(-2165 4335);
DISPLAY 0.659574 (-2165 4335);
PAINT MONO (-2165 4335);
DISPLAY INVISIBLE (-2165 4335);
FORCEPROP 1 LASTPIN (-2175 4325) BN 5
J 0
(-2187 4333);
DISPLAY 0.680851 (-2187 4333);
PAINT GREEN (-2187 4333);
FORCEPROP 2 LAST CDS_LIB standard
J 0
(-2125 4325);
DISPLAY INVISIBLE (-2125 4325);
FORCEPROP 1 LAST BODY_TYPE PLUMBING
J 0
(-2125 4375);
DISPLAY 0.872340 (-2125 4375);
PAINT GREEN (-2125 4375);
DISPLAY INVISIBLE (-2125 4375);
FORCEPROP 1 LAST HDL_TAP TRUE
J 0
(-1800 4200);
DISPLAY 0.872340 (-1800 4200);
DISPLAY INVISIBLE (-1800 4200);
FORCEPROP 1 LAST PATH I33
J 0
(-2127 4325);
DISPLAY 0.872340 (-2127 4325);
PAINT GREEN (-2127 4325);
DISPLAY INVISIBLE (-2127 4325);
FORCEADD TAP..1
(-2125 4675);
FORCEPROP 3 LASTPIN (-2175 4675) SIG_NAME P5E_CPU1_P2_RX_BUF_DN<6>
J 0
(-2165 4685);
DISPLAY 0.659574 (-2165 4685);
PAINT MONO (-2165 4685);
DISPLAY INVISIBLE (-2165 4685);
FORCEPROP 1 LASTPIN (-2175 4675) BN 6
J 0
(-2187 4683);
DISPLAY 0.680851 (-2187 4683);
PAINT GREEN (-2187 4683);
FORCEPROP 2 LAST CDS_LIB standard
J 0
(-2125 4675);
DISPLAY INVISIBLE (-2125 4675);
FORCEPROP 1 LAST BODY_TYPE PLUMBING
J 0
(-2125 4725);
DISPLAY 0.872340 (-2125 4725);
PAINT GREEN (-2125 4725);
DISPLAY INVISIBLE (-2125 4725);
FORCEPROP 1 LAST HDL_TAP TRUE
J 0
(-1800 4550);
DISPLAY 0.872340 (-1800 4550);
DISPLAY INVISIBLE (-1800 4550);
FORCEPROP 1 LAST PATH I34
J 0
(-2127 4675);
DISPLAY 0.872340 (-2127 4675);
PAINT GREEN (-2127 4675);
DISPLAY INVISIBLE (-2127 4675);
FORCEADD TAP..1
(-2125 5025);
FORCEPROP 3 LASTPIN (-2175 5025) SIG_NAME P5E_CPU1_P2_RX_BUF_DN<7>
J 0
(-2165 5035);
DISPLAY 0.659574 (-2165 5035);
PAINT MONO (-2165 5035);
DISPLAY INVISIBLE (-2165 5035);
FORCEPROP 1 LASTPIN (-2175 5025) BN 7
J 0
(-2187 5033);
DISPLAY 0.680851 (-2187 5033);
PAINT GREEN (-2187 5033);
FORCEPROP 2 LAST CDS_LIB standard
J 0
(-2125 5025);
DISPLAY INVISIBLE (-2125 5025);
FORCEPROP 1 LAST BODY_TYPE PLUMBING
J 0
(-2125 5075);
DISPLAY 0.872340 (-2125 5075);
PAINT GREEN (-2125 5075);
DISPLAY INVISIBLE (-2125 5075);
FORCEPROP 1 LAST HDL_TAP TRUE
J 0
(-1800 4900);
DISPLAY 0.872340 (-1800 4900);
DISPLAY INVISIBLE (-1800 4900);
FORCEPROP 1 LAST PATH I35
J 0
(-2127 5025);
DISPLAY 0.872340 (-2127 5025);
PAINT GREEN (-2127 5025);
DISPLAY INVISIBLE (-2127 5025);
FORCEADD OFFPAGE..1
R 2
(-1100 5150);
FORCEPROP 2 LAST $XR0 120 
J 0
(-914 5150);
DISPLAY 0.638298 (-914 5150);
PAINT MONO (-914 5150);
FORCEPROP 2 LAST CDS_LIB standard
J 0
(-1100 5150);
DISPLAY INVISIBLE (-1100 5150);
FORCEPROP 1 LAST OFFPAGE TRUE
J 2
(-1425 5025);
DISPLAY 0.872340 (-1425 5025);
DISPLAY INVISIBLE (-1425 5025);
FORCEPROP 1 LAST COMMENT_BODY TRUE
J 2
(-1225 5050);
DISPLAY 0.872340 (-1225 5050);
PAINT GREEN (-1225 5050);
DISPLAY INVISIBLE (-1225 5050);
FORCEPROP 2 LAST PATH I36
J 0
(-925 5225);
DISPLAY 0.680851 (-925 5225);
DISPLAY INVISIBLE (-925 5225);
FORCEADD OFFPAGE..1
R 2
(-1100 5225);
FORCEPROP 2 LAST $XR0 120 
J 0
(-914 5225);
DISPLAY 0.638298 (-914 5225);
PAINT MONO (-914 5225);
FORCEPROP 2 LAST CDS_LIB standard
J 0
(-1100 5225);
DISPLAY INVISIBLE (-1100 5225);
FORCEPROP 1 LAST OFFPAGE TRUE
J 2
(-1425 5100);
DISPLAY 0.872340 (-1425 5100);
DISPLAY INVISIBLE (-1425 5100);
FORCEPROP 1 LAST COMMENT_BODY TRUE
J 2
(-1225 5125);
DISPLAY 0.872340 (-1225 5125);
PAINT GREEN (-1225 5125);
DISPLAY INVISIBLE (-1225 5125);
FORCEPROP 2 LAST PATH I37
J 0
(-925 5300);
DISPLAY 0.680851 (-925 5300);
DISPLAY INVISIBLE (-925 5300);
FORCEADD PT5161LRS..2
(-3350 3875);
FORCEPROP 1 LAST LOCATION U6016
J 0
(-3700 5500);
DISPLAY 0.723404 (-3700 5500);
PAINT GREEN (-3700 5500);
FORCEPROP 0 LAST $SEC 2
J 0
(-3700 5650);
DISPLAY 0.680851 (-3700 5650);
PAINT MONO (-3700 5650);
DISPLAY INVISIBLE (-3700 5650);
FORCEPROP 0 LAST CDS_SEC 2
J 0
(-3700 5650);
DISPLAY 0.680851 (-3700 5650);
DISPLAY INVISIBLE (-3700 5650);
FORCEPROP 0 LASTPIN (-2900 5025) $PN CJ2
J 0
(-2890 5035);
DISPLAY 0.680851 (-2890 5035);
PAINT MONO (-2890 5035);
FORCEPROP 0 LASTPIN (-2900 4675) $PN CT2
J 0
(-2890 4685);
DISPLAY 0.680851 (-2890 4685);
PAINT MONO (-2890 4685);
FORCEPROP 0 LASTPIN (-2900 4325) $PN DC2
J 0
(-2890 4335);
DISPLAY 0.680851 (-2890 4335);
PAINT MONO (-2890 4335);
FORCEPROP 0 LASTPIN (-2900 3975) $PN DK2
J 0
(-2890 3985);
DISPLAY 0.680851 (-2890 3985);
PAINT MONO (-2890 3985);
FORCEPROP 0 LASTPIN (-2900 3625) $PN DU2
J 0
(-2890 3635);
DISPLAY 0.680851 (-2890 3635);
PAINT MONO (-2890 3635);
FORCEPROP 0 LASTPIN (-2900 3275) $PN ED2
J 0
(-2890 3285);
DISPLAY 0.680851 (-2890 3285);
PAINT MONO (-2890 3285);
FORCEPROP 0 LASTPIN (-2900 2925) $PN EL2
J 0
(-2890 2935);
DISPLAY 0.680851 (-2890 2935);
PAINT MONO (-2890 2935);
FORCEPROP 0 LASTPIN (-2900 2575) $PN EV2
J 0
(-2890 2585);
DISPLAY 0.680851 (-2890 2585);
PAINT MONO (-2890 2585);
FORCEPROP 0 LASTPIN (-2900 5125) $PN CL1
J 0
(-2890 5135);
DISPLAY 0.680851 (-2890 5135);
PAINT MONO (-2890 5135);
FORCEPROP 0 LASTPIN (-2900 4775) $PN CV1
J 0
(-2890 4785);
DISPLAY 0.680851 (-2890 4785);
PAINT MONO (-2890 4785);
FORCEPROP 0 LASTPIN (-2900 4425) $PN DE1
J 0
(-2890 4435);
DISPLAY 0.680851 (-2890 4435);
PAINT MONO (-2890 4435);
FORCEPROP 0 LASTPIN (-2900 4075) $PN DM1
J 0
(-2890 4085);
DISPLAY 0.680851 (-2890 4085);
PAINT MONO (-2890 4085);
FORCEPROP 0 LASTPIN (-2900 3725) $PN DW1
J 0
(-2890 3735);
DISPLAY 0.680851 (-2890 3735);
PAINT MONO (-2890 3735);
FORCEPROP 0 LASTPIN (-2900 3375) $PN EF1
J 0
(-2890 3385);
DISPLAY 0.680851 (-2890 3385);
PAINT MONO (-2890 3385);
FORCEPROP 0 LASTPIN (-2900 3025) $PN EN1
J 0
(-2890 3035);
DISPLAY 0.680851 (-2890 3035);
PAINT MONO (-2890 3035);
FORCEPROP 0 LASTPIN (-2900 2675) $PN EY1
J 0
(-2890 2685);
DISPLAY 0.680851 (-2890 2685);
PAINT MONO (-2890 2685);
FORCEPROP 2 LAST PART_TYPE SMLF
J 0
(-3700 5600);
DISPLAY 0.680851 (-3700 5600);
FORCEPROP 1 LAST MATERIAL IC
J 0
(-3700 5350);
DISPLAY 0.723404 (-3700 5350);
PAINT GREEN (-3700 5350);
FORCEPROP 2 LAST VALUE PT5161LRS
J 0
(-3700 5550);
DISPLAY 0.680851 (-3700 5550);
FORCEPROP 2 LAST CDS_LIB pure_quanta
J 0
(-3350 3875);
DISPLAY INVISIBLE (-3350 3875);
FORCEPROP 1 LAST CDS_LMAN_SYM_OUTLINE -350,1450,300,-1400
J 0
(-3350 3875);
DISPLAY 0.468085 (-3350 3875);
PAINT GREEN (-3350 3875);
DISPLAY INVISIBLE (-3350 3875);
FORCEPROP 1 LAST NEEDS_NO_SIZE TRUE
J 0
(-3350 3875);
DISPLAY 0.723404 (-3350 3875);
PAINT GREEN (-3350 3875);
DISPLAY INVISIBLE (-3350 3875);
FORCEPROP 1 LAST PATH I38
J 0
(-3350 3875);
DISPLAY 0.723404 (-3350 3875);
PAINT GREEN (-3350 3875);
DISPLAY INVISIBLE (-3350 3875);
FORCEPROP 1 LAST PART_NUMBER AJ051610U03
J 0
(-3700 5425);
DISPLAY 0.723404 (-3700 5425);
PAINT GREEN (-3700 5425);
DISPLAY INVISIBLE (-3700 5425);
FORCEADD TAP..1
(-6575 2550);
FORCEPROP 3 LASTPIN (-6625 2550) SIG_NAME P5E_CPU1_P2_RX_BUF_DN<8>
J 0
(-6615 2560);
DISPLAY 0.659574 (-6615 2560);
PAINT MONO (-6615 2560);
DISPLAY INVISIBLE (-6615 2560);
FORCEPROP 1 LASTPIN (-6625 2550) BN 8
J 0
(-6637 2558);
DISPLAY 0.680851 (-6637 2558);
PAINT GREEN (-6637 2558);
FORCEPROP 2 LAST CDS_LIB standard
J 0
(-6575 2550);
DISPLAY INVISIBLE (-6575 2550);
FORCEPROP 1 LAST BODY_TYPE PLUMBING
J 0
(-6575 2600);
DISPLAY 0.872340 (-6575 2600);
PAINT GREEN (-6575 2600);
DISPLAY INVISIBLE (-6575 2600);
FORCEPROP 1 LAST HDL_TAP TRUE
J 0
(-6250 2425);
DISPLAY 0.872340 (-6250 2425);
DISPLAY INVISIBLE (-6250 2425);
FORCEPROP 1 LAST PATH I4
J 0
(-6577 2550);
DISPLAY 0.872340 (-6577 2550);
PAINT GREEN (-6577 2550);
DISPLAY INVISIBLE (-6577 2550);
FORCEADD TAP..1
(-6575 2900);
FORCEPROP 3 LASTPIN (-6625 2900) SIG_NAME P5E_CPU1_P2_RX_BUF_DN<9>
J 0
(-6615 2910);
DISPLAY 0.659574 (-6615 2910);
PAINT MONO (-6615 2910);
DISPLAY INVISIBLE (-6615 2910);
FORCEPROP 1 LASTPIN (-6625 2900) BN 9
J 0
(-6637 2908);
DISPLAY 0.680851 (-6637 2908);
PAINT GREEN (-6637 2908);
FORCEPROP 2 LAST CDS_LIB standard
J 0
(-6575 2900);
DISPLAY INVISIBLE (-6575 2900);
FORCEPROP 1 LAST BODY_TYPE PLUMBING
J 0
(-6575 2950);
DISPLAY 0.872340 (-6575 2950);
PAINT GREEN (-6575 2950);
DISPLAY INVISIBLE (-6575 2950);
FORCEPROP 1 LAST HDL_TAP TRUE
J 0
(-6250 2775);
DISPLAY 0.872340 (-6250 2775);
DISPLAY INVISIBLE (-6250 2775);
FORCEPROP 1 LAST PATH I5
J 0
(-6577 2900);
DISPLAY 0.872340 (-6577 2900);
PAINT GREEN (-6577 2900);
DISPLAY INVISIBLE (-6577 2900);
FORCEADD TAP..1
(-6775 3350);
FORCEPROP 3 LASTPIN (-6825 3350) SIG_NAME P5E_CPU1_P2_RX_BUF_DP<10>
J 0
(-6815 3360);
DISPLAY 0.659574 (-6815 3360);
PAINT MONO (-6815 3360);
DISPLAY INVISIBLE (-6815 3360);
FORCEPROP 1 LASTPIN (-6825 3350) BN 10
J 0
(-6837 3358);
DISPLAY 0.680851 (-6837 3358);
PAINT GREEN (-6837 3358);
FORCEPROP 2 LAST CDS_LIB standard
J 0
(-6775 3350);
DISPLAY INVISIBLE (-6775 3350);
FORCEPROP 1 LAST BODY_TYPE PLUMBING
J 0
(-6775 3400);
DISPLAY 0.872340 (-6775 3400);
PAINT GREEN (-6775 3400);
DISPLAY INVISIBLE (-6775 3400);
FORCEPROP 1 LAST HDL_TAP TRUE
J 0
(-6450 3225);
DISPLAY 0.872340 (-6450 3225);
DISPLAY INVISIBLE (-6450 3225);
FORCEPROP 1 LAST PATH I6
J 0
(-6777 3350);
DISPLAY 0.872340 (-6777 3350);
PAINT GREEN (-6777 3350);
DISPLAY INVISIBLE (-6777 3350);
FORCEADD TAP..1
(-6575 3250);
FORCEPROP 3 LASTPIN (-6625 3250) SIG_NAME P5E_CPU1_P2_RX_BUF_DN<10>
J 0
(-6615 3260);
DISPLAY 0.659574 (-6615 3260);
PAINT MONO (-6615 3260);
DISPLAY INVISIBLE (-6615 3260);
FORCEPROP 1 LASTPIN (-6625 3250) BN 10
J 0
(-6637 3258);
DISPLAY 0.680851 (-6637 3258);
PAINT GREEN (-6637 3258);
FORCEPROP 2 LAST CDS_LIB standard
J 0
(-6575 3250);
DISPLAY INVISIBLE (-6575 3250);
FORCEPROP 1 LAST BODY_TYPE PLUMBING
J 0
(-6575 3300);
DISPLAY 0.872340 (-6575 3300);
PAINT GREEN (-6575 3300);
DISPLAY INVISIBLE (-6575 3300);
FORCEPROP 1 LAST HDL_TAP TRUE
J 0
(-6250 3125);
DISPLAY 0.872340 (-6250 3125);
DISPLAY INVISIBLE (-6250 3125);
FORCEPROP 1 LAST PATH I7
J 0
(-6577 3250);
DISPLAY 0.872340 (-6577 3250);
PAINT GREEN (-6577 3250);
DISPLAY INVISIBLE (-6577 3250);
FORCEADD TAP..1
(-6775 3700);
FORCEPROP 3 LASTPIN (-6825 3700) SIG_NAME P5E_CPU1_P2_RX_BUF_DP<11>
J 0
(-6815 3710);
DISPLAY 0.659574 (-6815 3710);
PAINT MONO (-6815 3710);
DISPLAY INVISIBLE (-6815 3710);
FORCEPROP 1 LASTPIN (-6825 3700) BN 11
J 0
(-6837 3708);
DISPLAY 0.680851 (-6837 3708);
PAINT GREEN (-6837 3708);
FORCEPROP 2 LAST CDS_LIB standard
J 0
(-6775 3700);
DISPLAY INVISIBLE (-6775 3700);
FORCEPROP 1 LAST BODY_TYPE PLUMBING
J 0
(-6775 3750);
DISPLAY 0.872340 (-6775 3750);
PAINT GREEN (-6775 3750);
DISPLAY INVISIBLE (-6775 3750);
FORCEPROP 1 LAST HDL_TAP TRUE
J 0
(-6450 3575);
DISPLAY 0.872340 (-6450 3575);
DISPLAY INVISIBLE (-6450 3575);
FORCEPROP 1 LAST PATH I8
J 0
(-6777 3700);
DISPLAY 0.872340 (-6777 3700);
PAINT GREEN (-6777 3700);
DISPLAY INVISIBLE (-6777 3700);
FORCEADD TAP..1
(-6775 4050);
FORCEPROP 3 LASTPIN (-6825 4050) SIG_NAME P5E_CPU1_P2_RX_BUF_DP<12>
J 0
(-6815 4060);
DISPLAY 0.659574 (-6815 4060);
PAINT MONO (-6815 4060);
DISPLAY INVISIBLE (-6815 4060);
FORCEPROP 1 LASTPIN (-6825 4050) BN 12
J 0
(-6837 4058);
DISPLAY 0.680851 (-6837 4058);
PAINT GREEN (-6837 4058);
FORCEPROP 2 LAST CDS_LIB standard
J 0
(-6775 4050);
DISPLAY INVISIBLE (-6775 4050);
FORCEPROP 1 LAST BODY_TYPE PLUMBING
J 0
(-6775 4100);
DISPLAY 0.872340 (-6775 4100);
PAINT GREEN (-6775 4100);
DISPLAY INVISIBLE (-6775 4100);
FORCEPROP 1 LAST HDL_TAP TRUE
J 0
(-6450 3925);
DISPLAY 0.872340 (-6450 3925);
DISPLAY INVISIBLE (-6450 3925);
FORCEPROP 1 LAST PATH I9
J 0
(-6777 4050);
DISPLAY 0.872340 (-6777 4050);
PAINT GREEN (-6777 4050);
DISPLAY INVISIBLE (-6777 4050);
FORCEADD QUANTA_TITLE_BLOCK_C..1
(0 0);
FORCEPROP 0 LAST CDS_CON_LAST_MODIFIED Thu Sep 14 16:12:55 2023
J 0
(-1885 15);
DISPLAY INVISIBLE (-1885 15);
FORCEPROP 1 LAST CUSTOM_TXT_CDS <CON_LAST_MODIFIED>
J 0
(-1885 15);
DISPLAY 0.978723 (-1885 15);
FORCEPROP 2 LAST CUSTOM_TXT_CDS <XR_PAGE_TITLE>
J 0
(-7890 5250);
DISPLAY 0.638298 (-7890 5250);
PAINT PINK (-7890 5250);
DISPLAY INVISIBLE (-7890 5250);
FORCEPROP 1 LAST CUSTOM_TXT_CDS <NAME_2>
J 0
(-3175 50);
FORCEPROP 1 LAST CUSTOM_TXT_CDS <NAME_1>
J 0
(-3175 175);
FORCEPROP 1 LAST CUSTOM_TXT_CDS <Q_NUMBER>
J 0
(-1403 103);
DISPLAY 1.212766 (-1403 103);
FORCEPROP 1 LAST CUSTOM_TXT_CDS <Q_PROJ>
J 0
(-2382 102);
DISPLAY 1.212766 (-2382 102);
FORCEPROP 1 LAST CUSTOM_TXT_CDS <Q_REV>
J 0
(-184 103);
DISPLAY 1.212766 (-184 103);
FORCEPROP 1 LAST CUSTOM_TXT_CDS <CON_PAGE_NUM> OF <CON_TOTAL_PAGES>
J 0
(-446 18);
DISPLAY 0.978723 (-446 18);
FORCEPROP 1 LAST Q_TITLE RETIMER_CPU1_P2(3)
J 0
(-9366 26);
DISPLAY 2.446809 (-9366 26);
PAINT GREEN (-9366 26);
FORCEPROP 2 LAST CDS_LIB pure_quanta
J 0
(0 0);
DISPLAY INVISIBLE (0 0);
FORCEPROP 1 LAST CDS_LMAN_SYM_OUTLINE -9475,6775,100,-125
J 0
(0 0);
DISPLAY 0.468085 (0 0);
PAINT GREEN (0 0);
DISPLAY INVISIBLE (0 0);
FORCEPROP 2 LAST PAGE_BORDER TRUE
J 0
(-7890 5250);
DISPLAY 0.638298 (-7890 5250);
PAINT PINK (-7890 5250);
DISPLAY INVISIBLE (-7890 5250);
FORCEPROP 2 LAST CDS_XR_PAGE_TITLE CR-341 : @T6G_MB_LIB.T6G(SCH_1):PAGE341
J 0
(-7890 5250);
DISPLAY 0.638298 (-7890 5250);
PAINT PINK (-7890 5250);
DISPLAY INVISIBLE (-7890 5250);
FORCEPROP 1 LAST Q_DEPT BU9
J 1
(-3763 49);
DISPLAY 1.957447 (-3763 49);
PAINT GREEN (-3763 49);
DISPLAY INVISIBLE (-3763 49);
FORCEPROP 1 LAST COMMENT_BODY TRUE
J 0
(12 -13);
DISPLAY 0.978723 (12 -13);
PAINT GREEN (12 -13);
DISPLAY INVISIBLE (12 -13);
WIRE 17 -1 (-2075 5150)(-2075 5050);
WIRE 17 -1 (-2075 5150)(-1150 5150);
FORCEPROP 2 LAST SIG_NAME P5E_CPU1_P2_RX_BUF_DN<7:0>
J 0
(-2010 5160);
DISPLAY 0.680851 (-2010 5160);
PAINT WHITE (-2010 5160);
WIRE 17 -1 (-2075 5050)(-2075 4700);
WIRE 17 -1 (-2075 4700)(-2075 4350);
WIRE 17 -1 (-2075 4350)(-2075 4000);
WIRE 17 -1 (-2075 3650)(-2075 3300);
WIRE 17 -1 (-2075 3650)(-2075 4000);
WIRE 17 -1 (-2075 3300)(-2075 2950);
WIRE 17 -1 (-2075 2950)(-2075 2600);
WIRE 17 -1 (-2275 3050)(-2275 2700);
WIRE 17 -1 (-2275 3400)(-2275 3050);
WIRE 17 -1 (-2275 3750)(-2275 3400);
WIRE 17 -1 (-2275 3750)(-2275 4100);
WIRE 17 -1 (-2275 4450)(-2275 4100);
WIRE 17 -1 (-2275 4800)(-2275 4450);
WIRE 17 -1 (-2275 5150)(-2275 4800);
WIRE 17 -1 (-2275 5225)(-2275 5150);
WIRE 17 -1 (-2275 5225)(-1150 5225);
FORCEPROP 2 LAST SIG_NAME P5E_CPU1_P2_RX_BUF_DP<7:0>
J 0
(-2010 5235);
DISPLAY 0.680851 (-2010 5235);
PAINT WHITE (-2010 5235);
WIRE 17 -1 (-6525 2925)(-6525 2575);
WIRE 17 -1 (-6525 3275)(-6525 2925);
WIRE 17 -1 (-6525 3625)(-6525 3275);
WIRE 17 -1 (-6525 3625)(-6525 3975);
WIRE 17 -1 (-6525 4325)(-6525 3975);
WIRE 17 -1 (-6525 4675)(-6525 4325);
WIRE 17 -1 (-6525 5025)(-6525 4675);
WIRE 17 -1 (-6525 5125)(-6525 5025);
WIRE 17 -1 (-6525 5125)(-5600 5125);
FORCEPROP 2 LAST SIG_NAME P5E_CPU1_P2_RX_BUF_DN<15:8>
J 0
(-6460 5135);
DISPLAY 0.680851 (-6460 5135);
PAINT WHITE (-6460 5135);
WIRE 17 -1 (-6725 5125)(-6725 4775);
WIRE 17 -1 (-6725 5200)(-6725 5125);
WIRE 17 -1 (-6725 4775)(-6725 4425);
WIRE 17 -1 (-6725 4425)(-6725 4075);
WIRE 17 -1 (-6725 5200)(-5600 5200);
FORCEPROP 2 LAST SIG_NAME P5E_CPU1_P2_RX_BUF_DP<15:8>
J 0
(-6460 5210);
DISPLAY 0.680851 (-6460 5210);
PAINT WHITE (-6460 5210);
WIRE 17 -1 (-6725 3725)(-6725 3375);
WIRE 17 -1 (-6725 3725)(-6725 4075);
WIRE 17 -1 (-6725 3375)(-6725 3025);
WIRE 17 -1 (-6725 3025)(-6725 2675);
WIRE 16 -1 (-7350 2900)(-6625 2900);
WIRE 16 -1 (-7350 3950)(-6625 3950);
WIRE 16 -1 (-7350 4400)(-6825 4400);
WIRE 16 -1 (-2900 3025)(-2375 3025);
WIRE 16 -1 (-2900 3725)(-2375 3725);
WIRE 16 -1 (-2900 3975)(-2175 3975);
WIRE 16 -1 (-2900 3625)(-2175 3625);
WIRE 16 -1 (-2900 2575)(-2175 2575);
WIRE 16 -1 (-2900 4775)(-2375 4775);
WIRE 16 -1 (-2900 4075)(-2375 4075);
WIRE 16 -1 (-2900 5125)(-2375 5125);
WIRE 16 -1 (-2900 4325)(-2175 4325);
WIRE 16 -1 (-2900 3375)(-2375 3375);
WIRE 16 -1 (-7350 3700)(-6825 3700);
WIRE 16 -1 (-7350 4050)(-6825 4050);
WIRE 16 -1 (-7350 5000)(-6625 5000);
WIRE 16 -1 (-7350 5100)(-6825 5100);
WIRE 16 -1 (-7350 2650)(-6825 2650);
WIRE 16 -1 (-7350 3000)(-6825 3000);
WIRE 16 -1 (-7350 3250)(-6625 3250);
WIRE 16 -1 (-7350 3350)(-6825 3350);
WIRE 16 -1 (-7350 3600)(-6625 3600);
WIRE 16 -1 (-7350 4300)(-6625 4300);
WIRE 16 -1 (-7350 4650)(-6625 4650);
WIRE 16 -1 (-7350 4750)(-6825 4750);
WIRE 16 -1 (-7350 2550)(-6625 2550);
WIRE 16 -1 (-2900 4425)(-2375 4425);
WIRE 16 -1 (-2900 2675)(-2375 2675);
WIRE 16 -1 (-2900 2925)(-2175 2925);
WIRE 16 -1 (-2900 3275)(-2175 3275);
WIRE 16 -1 (-2900 4675)(-2175 4675);
WIRE 16 -1 (-2900 5025)(-2175 5025);
FORCENOTE
P5E_CPU1_P2_RX_BUF_DP/DN<0-15> LANE REVERSAL
(-8900 6300) 0;
DISPLAY LEFT (-8900 6300);
DISPLAY 2.000000 (-8900 6300);
FORCENOTE
EXAMAX TO RETIMER
(-8175 1725) 0;
DISPLAY LEFT (-8175 1725);
DISPLAY 3.148936 (-8175 1725);
FORCENOTE
EXAMAX TO RETIMER
(-3625 1700) 0;
DISPLAY LEFT (-3625 1700);
DISPLAY 3.148936 (-3625 1700);
QUIT
